(kicad_pcb
	(version 20240108)
	(generator "pcbnew")
	(generator_version "8.0")
	(general
		(thickness 1.586)
		(legacy_teardrops no)
	)
	(paper "A4")
	(title_block
		(title "GMSL Serializer")
		(date "2024-11-27")
		(rev "1.1.1")
		(company "Antmicro Ltd")
		(comment 1 "www.antmicro.com")
		(comment 9 "footprints 97-100 of 117")
	)
	(layers
		(0 "F.Cu" signal)
		(1 "In1.Cu" power)
		(2 "In2.Cu" power)
		(31 "B.Cu" signal)
		(32 "B.Adhes" user "B.Adhesive")
		(33 "F.Adhes" user "F.Adhesive")
		(34 "B.Paste" user)
		(35 "F.Paste" user)
		(36 "B.SilkS" user "B.Silkscreen")
		(37 "F.SilkS" user "F.Silkscreen")
		(38 "B.Mask" user)
		(39 "F.Mask" user)
		(40 "Dwgs.User" user "User.Drawings")
		(41 "Cmts.User" user "User.Comments")
		(42 "Eco1.User" user "User.Eco1")
		(43 "Eco2.User" user "User.Eco2")
		(44 "Edge.Cuts" user)
		(45 "Margin" user)
		(46 "B.CrtYd" user "B.Courtyard")
		(47 "F.CrtYd" user "F.Courtyard")
		(48 "B.Fab" user)
		(49 "F.Fab" user)
	)
	(footprint "antmicro-footprints:C_0402_1005Metric"
		(layer "F.Cu")
		(at 148.85 97.61 -45)
		(descr "Capacitor SMD 0402")
		(tags "capacitor SMD 0402")
		(property "Reference" "C20"
			(at 0.997021 -2.552655 -45)
			(unlocked yes)
			(layer "F.SilkS")
			(effects
				(font
					(size 0.7 0.7)
					(thickness 0.15)
				)
				(justify right bottom)
			)
		)
		(property "Value" "C_100n_0402"
			(at -1.022927 2.155213 135)
			(layer "F.Fab")
			(effects
				(font
					(size 0.7 0.7)
					(thickness 0.15)
				)
				(justify right bottom)
			)
		)
		(property "Footprint" "antmicro-footprints:C_0402_1005Metric"
			(at 0 0 -45)
			(layer "F.Fab")
			(hide yes)
			(effects
				(font
					(size 1.27 1.27)
					(thickness 0.15)
				)
			)
		)
		(property "Datasheet" "https://www.murata.com/products/productdetail?partno=GRM155R61H104KE14%23"
			(at 0 0 -45)
			(layer "F.Fab")
			(hide yes)
			(effects
				(font
					(size 1.27 1.27)
					(thickness 0.15)
				)
			)
		)
		(property "Author" "Antmicro"
			(at -25.423538 133.842152 0)
			(layer "F.Fab")
			(hide yes)
			(effects
				(font
					(size 1 1)
					(thickness 0.15)
				)
			)
		)
		(property "Dielectric" "X5R"
			(at -25.423538 133.842152 0)
			(layer "F.Fab")
			(hide yes)
			(effects
				(font
					(size 1 1)
					(thickness 0.15)
				)
			)
		)
		(property "License" "Apache-2.0"
			(at -25.423538 133.842152 0)
			(layer "F.Fab")
			(hide yes)
			(effects
				(font
					(size 1 1)
					(thickness 0.15)
				)
			)
		)
		(property "MPN" "GRM155R61H104KE14D"
			(at -25.423538 133.842152 0)
			(layer "F.Fab")
			(hide yes)
			(effects
				(font
					(size 1 1)
					(thickness 0.15)
				)
			)
		)
		(property "Manufacturer" "Murata"
			(at -25.423538 133.842152 0)
			(layer "F.Fab")
			(hide yes)
			(effects
				(font
					(size 1 1)
					(thickness 0.15)
				)
			)
		)
		(property "Val" "100n"
			(at -25.423538 133.842152 0)
			(layer "F.Fab")
			(hide yes)
			(effects
				(font
					(size 1 1)
					(thickness 0.15)
				)
			)
		)
		(property "Voltage" "50V"
			(at -25.423538 133.842152 0)
			(layer "F.Fab")
			(hide yes)
			(effects
				(font
					(size 1 1)
					(thickness 0.15)
				)
			)
		)
		(sheetname "Serializer")
		(sheetfile "serializer.kicad_sch")
		(attr smd)
		(fp_poly
			(pts
				(xy -0.925 -0.47) (xy 0.925 -0.47) (xy 0.925 0.47) (xy -0.925 0.47)
			)
			(stroke
				(width 0.05)
				(type default)
			)
			(fill none)
			(layer "F.CrtYd")
		)
		(fp_line
			(start -0.494 0.248)
			(end -0.494 -0.25)
			(stroke
				(width 0.15)
				(type solid)
			)
			(layer "F.Fab")
		)
		(fp_line
			(start -0.494 -0.25)
			(end 0.504 -0.25)
			(stroke
				(width 0.15)
				(type solid)
			)
			(layer "F.Fab")
		)
		(fp_line
			(start 0.504 0.248)
			(end -0.494 0.248)
			(stroke
				(width 0.15)
				(type solid)
			)
			(layer "F.Fab")
		)
		(fp_line
			(start 0.504 -0.25)
			(end 0.504 0.248)
			(stroke
				(width 0.15)
				(type solid)
			)
			(layer "F.Fab")
		)
		(fp_text user "Author: Antmicro"
			(at -0.939 3.399 135)
			(layer "F.Fab")
			(hide yes)
			(effects
				(font
					(size 0.7 0.7)
					(thickness 0.15)
				)
				(justify right bottom)
			)
		)
		(fp_text user "License: Apache-2.0"
			(at -0.939 5.799 135)
			(layer "F.Fab")
			(hide yes)
			(effects
				(font
					(size 0.7 0.7)
					(thickness 0.15)
				)
				(justify right bottom)
			)
		)
		(fp_text user "${REFERENCE}"
			(at -0.939 4.599 135)
			(layer "F.Fab")
			(hide yes)
			(effects
				(font
					(size 0.7 0.7)
					(thickness 0.15)
				)
				(justify right bottom)
			)
		)
		(pad "1" smd roundrect
			(at -0.48 0 315)
			(size 0.59 0.64)
			(layers "F.Cu" "F.Paste" "F.Mask")
			(roundrect_rratio 0.25)
			(net 1 "GND")
			(pintype "passive")
		)
		(pad "2" smd roundrect
			(at 0.48 0 315)
			(size 0.59 0.64)
			(layers "F.Cu" "F.Paste" "F.Mask")
			(roundrect_rratio 0.25)
			(net 12 "+1V2")
			(pintype "passive")
		)
	)
	(footprint "antmicro-footprints:C_0402_1005Metric"
		(layer "F.Cu")
		(at 139.56 84.850142 -90)
		(descr "Capacitor SMD 0402")
		(tags "capacitor SMD 0402")
		(property "Reference" "C21"
			(at 0.609858 0.11 90)
			(layer "F.SilkS")
			(effects
				(font
					(size 0.7 0.7)
					(thickness 0.15)
				)
				(justify right top)
			)
		)
		(property "Value" "C_220n_0402"
			(at -1.022927 2.155213 90)
			(layer "F.Fab")
			(effects
				(font
					(size 0.7 0.7)
					(thickness 0.15)
				)
				(justify right top)
			)
		)
		(property "Footprint" "antmicro-footprints:C_0402_1005Metric"
			(at 0 0 90)
			(layer "F.Fab")
			(hide yes)
			(effects
				(font
					(size 1.27 1.27)
					(thickness 0.15)
				)
			)
		)
		(property "Datasheet" "https://www.yageo.com/en/Chart/Download/pdf/CC0402KRX5R6BB224"
			(at 0 0 90)
			(layer "F.Fab")
			(hide yes)
			(effects
				(font
					(size 1.27 1.27)
					(thickness 0.15)
				)
			)
		)
		(property "MPN" "CC0402KRX5R6BB224"
			(at 0 0 -90)
			(unlocked yes)
			(layer "F.Fab")
			(hide yes)
			(effects
				(font
					(size 1 1)
					(thickness 0.15)
				)
			)
		)
		(property "Manufacturer" "YAGEO"
			(at 0 0 -90)
			(unlocked yes)
			(layer "F.Fab")
			(hide yes)
			(effects
				(font
					(size 1 1)
					(thickness 0.15)
				)
			)
		)
		(property "License" "Apache-2.0"
			(at 0 0 -90)
			(unlocked yes)
			(layer "F.Fab")
			(hide yes)
			(effects
				(font
					(size 1 1)
					(thickness 0.15)
				)
			)
		)
		(property "Author" "Antmicro"
			(at 0 0 -90)
			(unlocked yes)
			(layer "F.Fab")
			(hide yes)
			(effects
				(font
					(size 1 1)
					(thickness 0.15)
				)
			)
		)
		(property "Val" "220n"
			(at 0 0 -90)
			(unlocked yes)
			(layer "F.Fab")
			(hide yes)
			(effects
				(font
					(size 1 1)
					(thickness 0.15)
				)
			)
		)
		(property "Voltage" ""
			(at 0 0 -90)
			(unlocked yes)
			(layer "F.Fab")
			(hide yes)
			(effects
				(font
					(size 1 1)
					(thickness 0.15)
				)
			)
		)
		(property "Dielectric" ""
			(at 0 0 -90)
			(unlocked yes)
			(layer "F.Fab")
			(hide yes)
			(effects
				(font
					(size 1 1)
					(thickness 0.15)
				)
			)
		)
		(sheetname "Supply")
		(sheetfile "supply.kicad_sch")
		(attr smd)
		(fp_rect
			(start -0.925 -0.47)
			(end 0.925 0.47)
			(stroke
				(width 0.05)
				(type default)
			)
			(fill none)
			(layer "F.CrtYd")
		)
		(fp_line
			(start -0.494 0.248)
			(end -0.494 -0.25)
			(stroke
				(width 0.15)
				(type solid)
			)
			(layer "F.Fab")
		)
		(fp_line
			(start 0.504 0.248)
			(end -0.494 0.248)
			(stroke
				(width 0.15)
				(type solid)
			)
			(layer "F.Fab")
		)
		(fp_line
			(start -0.494 -0.25)
			(end 0.504 -0.25)
			(stroke
				(width 0.15)
				(type solid)
			)
			(layer "F.Fab")
		)
		(fp_line
			(start 0.504 -0.25)
			(end 0.504 0.248)
			(stroke
				(width 0.15)
				(type solid)
			)
			(layer "F.Fab")
		)
		(fp_text user "License: Apache-2.0"
			(at -0.939 5.799 90)
			(layer "F.Fab")
			(hide yes)
			(effects
				(font
					(size 0.7 0.7)
					(thickness 0.15)
				)
				(justify right top)
			)
		)
		(fp_text user "${REFERENCE}"
			(at -0.939 4.599 90)
			(layer "F.Fab")
			(hide yes)
			(effects
				(font
					(size 0.7 0.7)
					(thickness 0.15)
				)
				(justify right top)
			)
		)
		(fp_text user "Author: Antmicro"
			(at -0.939 3.399 90)
			(layer "F.Fab")
			(hide yes)
			(effects
				(font
					(size 0.7 0.7)
					(thickness 0.15)
				)
				(justify right top)
			)
		)
		(pad "1" smd roundrect
			(at -0.48 0 270)
			(size 0.59 0.64)
			(layers "F.Cu" "F.Paste" "F.Mask")
			(roundrect_rratio 0.25)
			(net 93 "Net-(U3-BST)")
			(pintype "passive")
		)
		(pad "2" smd roundrect
			(at 0.48 0 270)
			(size 0.59 0.64)
			(layers "F.Cu" "F.Paste" "F.Mask")
			(roundrect_rratio 0.25)
			(net 72 "/Supply/SW_3V3")
			(pintype "passive")
		)
	)
	(footprint "antmicro-footprints:C_0402_1005Metric"
		(layer "F.Cu")
		(at 147.22 96.46 -45)
		(descr "Capacitor SMD 0402")
		(tags "capacitor SMD 0402")
		(property "Reference" "C29"
			(at 0.947523 -2.446589 -45)
			(unlocked yes)
			(layer "F.SilkS")
			(effects
				(font
					(size 0.7 0.7)
					(thickness 0.15)
				)
				(justify right bottom)
			)
		)
		(property "Value" "C_10n_0402"
			(at -1.022927 2.155213 135)
			(layer "F.Fab")
			(effects
				(font
					(size 0.7 0.7)
					(thickness 0.15)
				)
				(justify right bottom)
			)
		)
		(property "Footprint" "antmicro-footprints:C_0402_1005Metric"
			(at 0 0 -45)
			(layer "F.Fab")
			(hide yes)
			(effects
				(font
					(size 1.27 1.27)
					(thickness 0.15)
				)
			)
		)
		(property "Datasheet" "https://www.murata.com/products/productdetail?partno=GRM155R71H103KA88%23"
			(at 0 0 -45)
			(layer "F.Fab")
			(hide yes)
			(effects
				(font
					(size 1.27 1.27)
					(thickness 0.15)
				)
			)
		)
		(property "Author" "Antmicro"
			(at -25.087781 132.35274 0)
			(layer "F.Fab")
			(hide yes)
			(effects
				(font
					(size 1 1)
					(thickness 0.15)
				)
			)
		)
		(property "Dielectric" "X7R"
			(at -25.087781 132.35274 0)
			(layer "F.Fab")
			(hide yes)
			(effects
				(font
					(size 1 1)
					(thickness 0.15)
				)
			)
		)
		(property "License" "Apache-2.0"
			(at -25.087781 132.35274 0)
			(layer "F.Fab")
			(hide yes)
			(effects
				(font
					(size 1 1)
					(thickness 0.15)
				)
			)
		)
		(property "MPN" "GRM155R71H103KA88D"
			(at -25.087781 132.35274 0)
			(layer "F.Fab")
			(hide yes)
			(effects
				(font
					(size 1 1)
					(thickness 0.15)
				)
			)
		)
		(property "Manufacturer" "Murata"
			(at -25.087781 132.35274 0)
			(layer "F.Fab")
			(hide yes)
			(effects
				(font
					(size 1 1)
					(thickness 0.15)
				)
			)
		)
		(property "Val" "10n"
			(at -25.087781 132.35274 0)
			(layer "F.Fab")
			(hide yes)
			(effects
				(font
					(size 1 1)
					(thickness 0.15)
				)
			)
		)
		(property "Voltage" "50V"
			(at -25.087781 132.35274 0)
			(layer "F.Fab")
			(hide yes)
			(effects
				(font
					(size 1 1)
					(thickness 0.15)
				)
			)
		)
		(sheetname "Serializer")
		(sheetfile "serializer.kicad_sch")
		(attr smd)
		(fp_poly
			(pts
				(xy -0.925 -0.47) (xy 0.925 -0.47) (xy 0.925 0.47) (xy -0.925 0.47)
			)
			(stroke
				(width 0.05)
				(type default)
			)
			(fill none)
			(layer "F.CrtYd")
		)
		(fp_line
			(start -0.494 0.248)
			(end -0.494 -0.25)
			(stroke
				(width 0.15)
				(type solid)
			)
			(layer "F.Fab")
		)
		(fp_line
			(start -0.494 -0.25)
			(end 0.504 -0.25)
			(stroke
				(width 0.15)
				(type solid)
			)
			(layer "F.Fab")
		)
		(fp_line
			(start 0.504 0.248)
			(end -0.494 0.248)
			(stroke
				(width 0.15)
				(type solid)
			)
			(layer "F.Fab")
		)
		(fp_line
			(start 0.504 -0.25)
			(end 0.504 0.248)
			(stroke
				(width 0.15)
				(type solid)
			)
			(layer "F.Fab")
		)
		(fp_text user "License: Apache-2.0"
			(at -0.939 5.799 135)
			(layer "F.Fab")
			(hide yes)
			(effects
				(font
					(size 0.7 0.7)
					(thickness 0.15)
				)
				(justify right bottom)
			)
		)
		(fp_text user "${REFERENCE}"
			(at -0.939 4.599 135)
			(layer "F.Fab")
			(hide yes)
			(effects
				(font
					(size 0.7 0.7)
					(thickness 0.15)
				)
				(justify right bottom)
			)
		)
		(fp_text user "Author: Antmicro"
			(at -0.939 3.399 135)
			(layer "F.Fab")
			(hide yes)
			(effects
				(font
					(size 0.7 0.7)
					(thickness 0.15)
				)
				(justify right bottom)
			)
		)
		(pad "1" smd roundrect
			(at -0.48 0 315)
			(size 0.59 0.64)
			(layers "F.Cu" "F.Paste" "F.Mask")
			(roundrect_rratio 0.25)
			(net 1 "GND")
			(pintype "passive")
		)
		(pad "2" smd roundrect
			(at 0.48 0 315)
			(size 0.59 0.64)
			(layers "F.Cu" "F.Paste" "F.Mask")
			(roundrect_rratio 0.25)
			(net 10 "+3V3")
			(pintype "passive")
		)
	)
	(footprint "antmicro-footprints:R_0402_1005Metric"
		(layer "F.Cu")
		(at 163.95 97.125 180)
		(descr "Resistor SMD 0402")
		(tags "resistor SMD 0402")
		(property "Reference" "R26"
			(at -1.15 0.525 0)
			(layer "F.SilkS")
			(effects
				(font
					(size 0.7 0.7)
					(thickness 0.15)
				)
				(justify right bottom)
			)
		)
		(property "Value" "R_10k_0402"
			(at -1.011843 1.772047 0)
			(layer "F.Fab")
			(effects
				(font
					(size 0.7 0.7)
					(thickness 0.15)
				)
				(justify right bottom)
			)
		)
		(property "Footprint" "antmicro-footprints:R_0402_1005Metric"
			(at 0 0 180)
			(layer "F.Fab")
			(hide yes)
			(effects
				(font
					(size 1.27 1.27)
					(thickness 0.15)
				)
			)
		)
		(property "Datasheet" "https://www.bourns.com/docs/product-datasheets/cr.pdf"
			(at 0 0 180)
			(layer "F.Fab")
			(hide yes)
			(effects
				(font
					(size 1.27 1.27)
					(thickness 0.15)
				)
			)
		)
		(property "Author" "Antmicro"
			(at 327.9 194.25 0)
			(layer "F.Fab")
			(hide yes)
			(effects
				(font
					(size 1 1)
					(thickness 0.15)
				)
			)
		)
		(property "License" "Apache-2.0"
			(at 327.9 194.25 0)
			(layer "F.Fab")
			(hide yes)
			(effects
				(font
					(size 1 1)
					(thickness 0.15)
				)
			)
		)
		(property "MPN" "CR0402-FX-1002GLF"
			(at 327.9 194.25 0)
			(layer "F.Fab")
			(hide yes)
			(effects
				(font
					(size 1 1)
					(thickness 0.15)
				)
			)
		)
		(property "Manufacturer" "Bourns"
			(at 327.9 194.25 0)
			(layer "F.Fab")
			(hide yes)
			(effects
				(font
					(size 1 1)
					(thickness 0.15)
				)
			)
		)
		(property "Tolerance" "1%"
			(at 327.9 194.25 0)
			(layer "F.Fab")
			(hide yes)
			(effects
				(font
					(size 1 1)
					(thickness 0.15)
				)
			)
		)
		(property "Val" "10k"
			(at 327.9 194.25 0)
			(layer "F.Fab")
			(hide yes)
			(effects
				(font
					(size 1 1)
					(thickness 0.15)
				)
			)
		)
		(sheetname "Supply")
		(sheetfile "supply.kicad_sch")
		(attr smd)
		(fp_rect
			(start -0.925 -0.47)
			(end 0.925 0.47)
			(stroke
				(width 0.05)
				(type default)
			)
			(fill none)
			(layer "F.CrtYd")
		)
		(fp_rect
			(start -0.5 -0.25)
			(end 0.5 0.25)
			(stroke
				(width 0.15)
				(type solid)
			)
			(fill none)
			(layer "F.Fab")
		)
		(fp_text user "License: Apache-2.0"
			(at -0.95 5.169 0)
			(layer "F.Fab")
			(hide yes)
			(effects
				(font
					(size 0.7 0.7)
					(thickness 0.15)
				)
				(justify right bottom)
			)
		)
		(fp_text user "${REFERENCE}"
			(at -0.95 3.168 0)
			(layer "F.Fab")
			(hide yes)
			(effects
				(font
					(size 0.7 0.7)
					(thickness 0.15)
				)
				(justify right bottom)
			)
		)
		(fp_text user "Author: Antmicro"
			(at -0.95 4.169 0)
			(layer "F.Fab")
			(hide yes)
			(effects
				(font
					(size 0.7 0.7)
					(thickness 0.15)
				)
				(justify right bottom)
			)
		)
		(pad "1" smd roundrect
			(at -0.48 0 180)
			(size 0.59 0.64)
			(layers "F.Cu" "F.Paste" "F.Mask")
			(roundrect_rratio 0.25)
			(net 1 "GND")
			(pintype "passive")
		)
		(pad "2" smd roundrect
			(at 0.48 0 180)
			(size 0.59 0.64)
			(layers "F.Cu" "F.Paste" "F.Mask")
			(roundrect_rratio 0.25)
			(net 63 "/Supply/EN_1V8")
			(pintype "passive")
		)
	)
)
